(kicad_sch
	(version 20250114)
	(generator "eeschema")
	(generator_version "9.0")
	(paper "A3")
	(title_block
		(title "COM Express 7 Baseboard")
		(date "2025-02-04")
		(rev "1.1.2")
		(company "Antmicro Ltd")
		(comment 1 "www.antmicro.com")
	)
	(text "M.2 key E"
		(exclude_from_sim no)
		(at 182.88 49.53 0)
		(effects
			(font
				(size 2 2)
				(thickness 0.508)
				(bold yes)
			)
			(justify left bottom)
		)
	)
	(text "WiFi LED"
		(exclude_from_sim no)
		(at 234.95 170.18 0)
		(effects
			(font
				(size 1.27 1.27)
			)
			(justify left bottom)
		)
	)
	(text "Suggested card: Intel AC9260"
		(exclude_from_sim no)
		(at 184.15 195.58 0)
		(effects
			(font
				(size 1.27 1.27)
			)
			(justify left bottom)
		)
	)
	(text "BT LED"
		(exclude_from_sim no)
		(at 247.65 170.18 0)
		(effects
			(font
				(size 1.27 1.27)
			)
			(justify left bottom)
		)
	)
	(text "Swapped polarity of TX and RX lines\nfor easier PCB layout"
		(exclude_from_sim no)
		(at 137.668 135.128 0)
		(effects
			(font
				(size 1.27 1.27)
			)
			(justify left bottom)
		)
	)
	(junction
		(at 166.37 82.55)
		(diameter 0)
		(color 0 0 0 0)
	)
	(junction
		(at 175.26 85.09)
		(diameter 0)
		(color 0 0 0 0)
	)
	(junction
		(at 218.44 186.69)
		(diameter 0)
		(color 0 0 0 0)
	)
	(junction
		(at 166.37 74.93)
		(diameter 0)
		(color 0 0 0 0)
	)
	(junction
		(at 247.65 74.93)
		(diameter 0)
		(color 0 0 0 0)
	)
	(junction
		(at 238.76 74.93)
		(diameter 0)
		(color 0 0 0 0)
	)
	(junction
		(at 229.87 74.93)
		(diameter 0)
		(color 0 0 0 0)
	)
	(junction
		(at 220.98 74.93)
		(diameter 0)
		(color 0 0 0 0)
	)
	(no_connect
		(at 213.36 157.48)
	)
	(no_connect
		(at 213.36 160.02)
	)
	(no_connect
		(at 213.36 128.27)
	)
	(no_connect
		(at 182.88 181.61)
	)
	(no_connect
		(at 157.48 118.11)
	)
	(no_connect
		(at 182.88 151.13)
	)
	(no_connect
		(at 182.88 125.73)
	)
	(no_connect
		(at 182.88 186.69)
	)
	(no_connect
		(at 213.36 146.05)
	)
	(no_connect
		(at 182.88 176.53)
	)
	(no_connect
		(at 182.88 148.59)
	)
	(no_connect
		(at 182.88 156.21)
	)
	(no_connect
		(at 213.36 133.35)
	)
	(no_connect
		(at 182.88 133.35)
	)
	(no_connect
		(at 182.88 118.11)
	)
	(no_connect
		(at 213.36 110.49)
	)
	(no_connect
		(at 182.88 184.15)
	)
	(no_connect
		(at 182.88 168.91)
	)
	(no_connect
		(at 213.36 118.11)
	)
	(no_connect
		(at 213.36 113.03)
	)
	(no_connect
		(at 182.88 115.57)
	)
	(no_connect
		(at 213.36 148.59)
	)
	(no_connect
		(at 182.88 87.63)
	)
	(no_connect
		(at 182.88 153.67)
	)
	(no_connect
		(at 182.88 143.51)
	)
	(no_connect
		(at 182.88 140.97)
	)
	(no_connect
		(at 213.36 130.81)
	)
	(no_connect
		(at 213.36 162.56)
	)
	(no_connect
		(at 182.88 173.99)
	)
	(no_connect
		(at 157.48 125.73)
	)
	(no_connect
		(at 182.88 138.43)
	)
	(no_connect
		(at 213.36 120.65)
	)
	(no_connect
		(at 213.36 135.89)
	)
	(no_connect
		(at 157.48 120.65)
	)
	(no_connect
		(at 182.88 179.07)
	)
	(no_connect
		(at 182.88 123.19)
	)
	(no_connect
		(at 213.36 107.95)
	)
	(no_connect
		(at 182.88 130.81)
	)
	(no_connect
		(at 182.88 171.45)
	)
	(no_connect
		(at 213.36 125.73)
	)
	(no_connect
		(at 213.36 151.13)
	)
	(no_connect
		(at 157.48 128.27)
	)
	(bus_entry
		(at 139.7 118.11)
		(size -1.27 -1.27)
		(stroke
			(width 0)
			(type default)
		)
	)
	(bus_entry
		(at 138.43 161.29)
		(size 2.54 2.54)
		(stroke
			(width 0)
			(type default)
		)
	)
	(bus_entry
		(at 138.43 99.06)
		(size 1.27 1.27)
		(stroke
			(width 0)
			(type default)
		)
	)
	(bus_entry
		(at 138.43 106.68)
		(size 1.27 1.27)
		(stroke
			(width 0)
			(type default)
		)
	)
	(bus_entry
		(at 138.43 158.75)
		(size 2.54 2.54)
		(stroke
			(width 0)
			(type default)
		)
	)
	(bus_entry
		(at 139.7 128.27)
		(size -1.27 -1.27)
		(stroke
			(width 0)
			(type default)
		)
	)
	(bus_entry
		(at 158.75 92.71)
		(size -1.27 -1.27)
		(stroke
			(width 0)
			(type default)
		)
	)
	(bus_entry
		(at 138.43 109.22)
		(size 1.27 1.27)
		(stroke
			(width 0)
			(type default)
		)
	)
	(bus_entry
		(at 158.75 95.25)
		(size -1.27 -1.27)
		(stroke
			(width 0)
			(type default)
		)
	)
	(bus_entry
		(at 138.43 101.6)
		(size 1.27 1.27)
		(stroke
			(width 0)
			(type default)
		)
	)
	(bus_entry
		(at 139.7 120.65)
		(size -1.27 -1.27)
		(stroke
			(width 0)
			(type default)
		)
	)
	(bus_entry
		(at 139.7 125.73)
		(size -1.27 -1.27)
		(stroke
			(width 0)
			(type default)
		)
	)
	(wire
		(pts
			(xy 175.26 95.25) (xy 158.75 95.25)
		)
		(stroke
			(width 0)
			(type default)
		)
	)
	(wire
		(pts
			(xy 139.7 100.33) (xy 161.29 100.33)
		)
		(stroke
			(width 0)
			(type default)
		)
	)
	(wire
		(pts
			(xy 166.37 73.66) (xy 166.37 74.93)
		)
		(stroke
			(width 0)
			(type default)
		)
	)
	(bus
		(pts
			(xy 156.21 87.63) (xy 132.08 87.63)
		)
		(stroke
			(width 0)
			(type default)
		)
	)
	(wire
		(pts
			(xy 229.87 83.82) (xy 229.87 82.55)
		)
		(stroke
			(width 0)
			(type default)
		)
	)
	(bus
		(pts
			(xy 157.48 88.9) (xy 156.21 87.63)
		)
		(stroke
			(width 0)
			(type default)
		)
	)
	(wire
		(pts
			(xy 166.37 81.28) (xy 166.37 82.55)
		)
		(stroke
			(width 0)
			(type default)
		)
	)
	(wire
		(pts
			(xy 247.65 72.39) (xy 247.65 74.93)
		)
		(stroke
			(width 0)
			(type default)
		)
	)
	(bus
		(pts
			(xy 157.48 93.98) (xy 157.48 91.44)
		)
		(stroke
			(width 0)
			(type default)
		)
	)
	(wire
		(pts
			(xy 215.9 74.93) (xy 215.9 82.55)
		)
		(stroke
			(width 0)
			(type default)
		)
	)
	(bus
		(pts
			(xy 132.08 77.47) (xy 137.16 77.47)
		)
		(stroke
			(width 0)
			(type default)
		)
	)
	(wire
		(pts
			(xy 248.92 228.6) (xy 248.92 227.33)
		)
		(stroke
			(width 0)
			(type default)
		)
	)
	(bus
		(pts
			(xy 137.16 156.21) (xy 138.43 157.48)
		)
		(stroke
			(width 0)
			(type default)
		)
	)
	(wire
		(pts
			(xy 213.36 186.69) (xy 218.44 186.69)
		)
		(stroke
			(width 0)
			(type default)
		)
	)
	(wire
		(pts
			(xy 238.76 74.93) (xy 238.76 77.47)
		)
		(stroke
			(width 0)
			(type default)
		)
	)
	(wire
		(pts
			(xy 182.88 95.25) (xy 177.8 95.25)
		)
		(stroke
			(width 0)
			(type default)
		)
	)
	(bus
		(pts
			(xy 138.43 78.74) (xy 138.43 99.06)
		)
		(stroke
			(width 0)
			(type default)
		)
	)
	(wire
		(pts
			(xy 247.65 158.75) (xy 247.65 160.02)
		)
		(stroke
			(width 0)
			(type default)
		)
	)
	(wire
		(pts
			(xy 163.83 100.33) (xy 161.29 102.87)
		)
		(stroke
			(width 0)
			(type default)
		)
	)
	(wire
		(pts
			(xy 247.65 165.1) (xy 247.65 172.72)
		)
		(stroke
			(width 0)
			(type default)
		)
	)
	(wire
		(pts
			(xy 229.87 74.93) (xy 229.87 77.47)
		)
		(stroke
			(width 0)
			(type default)
		)
	)
	(wire
		(pts
			(xy 220.98 83.82) (xy 220.98 82.55)
		)
		(stroke
			(width 0)
			(type default)
		)
	)
	(wire
		(pts
			(xy 163.83 100.33) (xy 182.88 100.33)
		)
		(stroke
			(width 0)
			(type default)
		)
	)
	(wire
		(pts
			(xy 157.48 118.11) (xy 139.7 118.11)
		)
		(stroke
			(width 0)
			(type default)
		)
	)
	(wire
		(pts
			(xy 218.44 186.69) (xy 218.44 187.96)
		)
		(stroke
			(width 0)
			(type default)
		)
	)
	(wire
		(pts
			(xy 238.76 83.82) (xy 238.76 82.55)
		)
		(stroke
			(width 0)
			(type default)
		)
	)
	(wire
		(pts
			(xy 234.95 165.1) (xy 234.95 167.64)
		)
		(stroke
			(width 0)
			(type default)
		)
	)
	(wire
		(pts
			(xy 175.26 92.71) (xy 158.75 92.71)
		)
		(stroke
			(width 0)
			(type default)
		)
	)
	(wire
		(pts
			(xy 163.83 107.95) (xy 161.29 110.49)
		)
		(stroke
			(width 0)
			(type default)
		)
	)
	(wire
		(pts
			(xy 175.26 85.09) (xy 182.88 85.09)
		)
		(stroke
			(width 0)
			(type default)
		)
	)
	(bus
		(pts
			(xy 133.35 156.21) (xy 137.16 156.21)
		)
		(stroke
			(width 0)
			(type default)
		)
	)
	(bus
		(pts
			(xy 138.43 116.84) (xy 138.43 119.38)
		)
		(stroke
			(width 0)
			(type default)
		)
	)
	(wire
		(pts
			(xy 157.48 128.27) (xy 139.7 128.27)
		)
		(stroke
			(width 0)
			(type default)
		)
	)
	(wire
		(pts
			(xy 220.98 74.93) (xy 220.98 77.47)
		)
		(stroke
			(width 0)
			(type default)
		)
	)
	(bus
		(pts
			(xy 138.43 99.06) (xy 138.43 101.6)
		)
		(stroke
			(width 0)
			(type default)
		)
	)
	(wire
		(pts
			(xy 132.08 82.55) (xy 144.78 82.55)
		)
		(stroke
			(width 0)
			(type default)
		)
	)
	(wire
		(pts
			(xy 166.37 82.55) (xy 182.88 82.55)
		)
		(stroke
			(width 0)
			(type default)
		)
	)
	(wire
		(pts
			(xy 161.29 107.95) (xy 163.83 110.49)
		)
		(stroke
			(width 0)
			(type default)
		)
	)
	(wire
		(pts
			(xy 227.33 95.25) (xy 237.49 95.25)
		)
		(stroke
			(width 0)
			(type default)
		)
	)
	(wire
		(pts
			(xy 140.97 163.83) (xy 154.94 163.83)
		)
		(stroke
			(width 0)
			(type default)
		)
	)
	(wire
		(pts
			(xy 213.36 184.15) (xy 218.44 184.15)
		)
		(stroke
			(width 0)
			(type default)
		)
	)
	(wire
		(pts
			(xy 213.36 167.64) (xy 234.95 167.64)
		)
		(stroke
			(width 0)
			(type default)
		)
	)
	(wire
		(pts
			(xy 161.29 110.49) (xy 139.7 110.49)
		)
		(stroke
			(width 0)
			(type default)
		)
	)
	(wire
		(pts
			(xy 234.95 158.75) (xy 234.95 160.02)
		)
		(stroke
			(width 0)
			(type default)
		)
	)
	(bus
		(pts
			(xy 138.43 124.46) (xy 138.43 127)
		)
		(stroke
			(width 0)
			(type default)
		)
	)
	(wire
		(pts
			(xy 175.26 74.93) (xy 175.26 76.2)
		)
		(stroke
			(width 0)
			(type default)
		)
	)
	(wire
		(pts
			(xy 157.48 125.73) (xy 139.7 125.73)
		)
		(stroke
			(width 0)
			(type default)
		)
	)
	(wire
		(pts
			(xy 182.88 92.71) (xy 177.8 92.71)
		)
		(stroke
			(width 0)
			(type default)
		)
	)
	(wire
		(pts
			(xy 132.08 85.09) (xy 175.26 85.09)
		)
		(stroke
			(width 0)
			(type default)
		)
	)
	(bus
		(pts
			(xy 138.43 158.75) (xy 138.43 161.29)
		)
		(stroke
			(width 0)
			(type default)
		)
	)
	(wire
		(pts
			(xy 247.65 74.93) (xy 247.65 77.47)
		)
		(stroke
			(width 0)
			(type default)
		)
	)
	(bus
		(pts
			(xy 138.43 157.48) (xy 138.43 158.75)
		)
		(stroke
			(width 0)
			(type default)
		)
	)
	(wire
		(pts
			(xy 175.26 92.71) (xy 177.8 95.25)
		)
		(stroke
			(width 0)
			(type default)
		)
	)
	(wire
		(pts
			(xy 175.26 81.28) (xy 175.26 85.09)
		)
		(stroke
			(width 0)
			(type default)
		)
	)
	(wire
		(pts
			(xy 177.8 92.71) (xy 175.26 95.25)
		)
		(stroke
			(width 0)
			(type default)
		)
	)
	(wire
		(pts
			(xy 149.86 82.55) (xy 166.37 82.55)
		)
		(stroke
			(width 0)
			(type default)
		)
	)
	(wire
		(pts
			(xy 247.65 83.82) (xy 247.65 82.55)
		)
		(stroke
			(width 0)
			(type default)
		)
	)
	(wire
		(pts
			(xy 215.9 74.93) (xy 220.98 74.93)
		)
		(stroke
			(width 0)
			(type default)
		)
	)
	(wire
		(pts
			(xy 163.83 102.87) (xy 182.88 102.87)
		)
		(stroke
			(width 0)
			(type default)
		)
	)
	(bus
		(pts
			(xy 138.43 106.68) (xy 138.43 109.22)
		)
		(stroke
			(width 0)
			(type default)
		)
	)
	(wire
		(pts
			(xy 215.9 82.55) (xy 213.36 82.55)
		)
		(stroke
			(width 0)
			(type default)
		)
	)
	(wire
		(pts
			(xy 160.02 163.83) (xy 182.88 163.83)
		)
		(stroke
			(width 0)
			(type default)
		)
	)
	(wire
		(pts
			(xy 213.36 95.25) (xy 222.25 95.25)
		)
		(stroke
			(width 0)
			(type default)
		)
	)
	(wire
		(pts
			(xy 218.44 184.15) (xy 218.44 186.69)
		)
		(stroke
			(width 0)
			(type default)
		)
	)
	(wire
		(pts
			(xy 229.87 74.93) (xy 238.76 74.93)
		)
		(stroke
			(width 0)
			(type default)
		)
	)
	(wire
		(pts
			(xy 248.92 227.33) (xy 250.19 227.33)
		)
		(stroke
			(width 0)
			(type default)
		)
	)
	(wire
		(pts
			(xy 161.29 100.33) (xy 163.83 102.87)
		)
		(stroke
			(width 0)
			(type default)
		)
	)
	(wire
		(pts
			(xy 182.88 110.49) (xy 163.83 110.49)
		)
		(stroke
			(width 0)
			(type default)
		)
	)
	(wire
		(pts
			(xy 220.98 74.93) (xy 229.87 74.93)
		)
		(stroke
			(width 0)
			(type default)
		)
	)
	(wire
		(pts
			(xy 157.48 120.65) (xy 139.7 120.65)
		)
		(stroke
			(width 0)
			(type default)
		)
	)
	(wire
		(pts
			(xy 238.76 74.93) (xy 247.65 74.93)
		)
		(stroke
			(width 0)
			(type default)
		)
	)
	(bus
		(pts
			(xy 157.48 91.44) (xy 157.48 88.9)
		)
		(stroke
			(width 0)
			(type default)
		)
	)
	(bus
		(pts
			(xy 138.43 101.6) (xy 138.43 106.68)
		)
		(stroke
			(width 0)
			(type default)
		)
	)
	(wire
		(pts
			(xy 160.02 161.29) (xy 182.88 161.29)
		)
		(stroke
			(width 0)
			(type default)
		)
	)
	(wire
		(pts
			(xy 161.29 107.95) (xy 139.7 107.95)
		)
		(stroke
			(width 0)
			(type default)
		)
	)
	(wire
		(pts
			(xy 166.37 74.93) (xy 166.37 76.2)
		)
		(stroke
			(width 0)
			(type default)
		)
	)
	(bus
		(pts
			(xy 137.16 77.47) (xy 138.43 78.74)
		)
		(stroke
			(width 0)
			(type default)
		)
	)
	(wire
		(pts
			(xy 182.88 107.95) (xy 163.83 107.95)
		)
		(stroke
			(width 0)
			(type default)
		)
	)
	(wire
		(pts
			(xy 175.26 74.93) (xy 166.37 74.93)
		)
		(stroke
			(width 0)
			(type default)
		)
	)
	(bus
		(pts
			(xy 138.43 119.38) (xy 138.43 124.46)
		)
		(stroke
			(width 0)
			(type default)
		)
	)
	(wire
		(pts
			(xy 139.7 102.87) (xy 161.29 102.87)
		)
		(stroke
			(width 0)
			(type default)
		)
	)
	(wire
		(pts
			(xy 213.36 172.72) (xy 247.65 172.72)
		)
		(stroke
			(width 0)
			(type default)
		)
	)
	(wire
		(pts
			(xy 140.97 161.29) (xy 154.94 161.29)
		)
		(stroke
			(width 0)
			(type default)
		)
	)
	(bus
		(pts
			(xy 138.43 109.22) (xy 138.43 116.84)
		)
		(stroke
			(width 0)
			(type default)
		)
	)
	(label "~{LED_1}"
		(at 218.44 167.64 0)
		(effects
			(font
				(size 1.27 1.27)
			)
			(justify left bottom)
		)
	)
	(label "PCIe_{x1}.TX0+"
		(at 140.97 100.33 0)
		(effects
			(font
				(size 1.27 1.27)
			)
			(justify left bottom)
		)
	)
	(label "PCIe_{x1}.RX0-"
		(at 140.97 110.49 0)
		(effects
			(font
				(size 1.27 1.27)
			)
			(justify left bottom)
		)
	)
	(label "USB.D+"
		(at 140.97 161.29 0)
		(effects
			(font
				(size 1.27 1.27)
			)
			(justify left bottom)
		)
	)
	(label "PCIe_{x1}.RX1+"
		(at 157.48 125.73 180)
		(effects
			(font
				(size 1.27 1.27)
			)
			(justify right bottom)
		)
	)
	(label "WIFI_BT_USB_D_P"
		(at 163.83 161.29 0)
		(effects
			(font
				(size 1.27 1.27)
			)
			(justify left bottom)
		)
	)
	(label "~{LED_2}"
		(at 218.44 172.72 0)
		(effects
			(font
				(size 1.27 1.27)
			)
			(justify left bottom)
		)
	)
	(label "PCIe_{x1}.RX1-"
		(at 157.48 128.27 180)
		(effects
			(font
				(size 1.27 1.27)
			)
			(justify right bottom)
		)
	)
	(label "PCIE_{REF}.CK-"
		(at 158.75 95.25 0)
		(effects
			(font
				(size 1.27 1.27)
			)
			(justify left bottom)
		)
	)
	(label "WIFI_BT_USB_D_N"
		(at 163.83 163.83 0)
		(effects
			(font
				(size 1.27 1.27)
			)
			(justify left bottom)
		)
	)
	(label "PCIe_{x1}.TX1-"
		(at 157.48 120.65 180)
		(effects
			(font
				(size 1.27 1.27)
			)
			(justify right bottom)
		)
	)
	(label "PCIe_{x1}.TX1+"
		(at 157.48 118.11 180)
		(effects
			(font
				(size 1.27 1.27)
			)
			(justify right bottom)
		)
	)
	(label "~{PERST_D}"
		(at 153.67 82.55 0)
		(effects
			(font
				(size 1.27 1.27)
			)
			(justify left bottom)
		)
	)
	(label "PCIE_{REF}.CK+"
		(at 158.75 92.71 0)
		(effects
			(font
				(size 1.27 1.27)
			)
			(justify left bottom)
		)
	)
	(label "USB.D-"
		(at 140.97 163.83 0)
		(effects
			(font
				(size 1.27 1.27)
			)
			(justify left bottom)
		)
	)
	(label "PCIe_{x1}.TX0-"
		(at 140.97 102.87 0)
		(effects
			(font
				(size 1.27 1.27)
			)
			(justify left bottom)
		)
	)
	(label "PCIe_{x1}.RX0+"
		(at 140.97 107.95 0)
		(effects
			(font
				(size 1.27 1.27)
			)
			(justify left bottom)
		)
	)
	(hierarchical_label "SUSCLK"
		(shape input)
		(at 237.49 95.25 0)
		(effects
			(font
				(size 1.27 1.27)
			)
			(justify left)
		)
	)
	(hierarchical_label "~{PERST}"
		(shape input)
		(at 132.08 82.55 180)
		(effects
			(font
				(size 1.27 1.27)
			)
			(justify right)
		)
	)
	(hierarchical_label "PCIE_{REF}{PCIe_{REF}}"
		(shape input)
		(at 132.08 87.63 180)
		(effects
			(font
				(size 1.27 1.27)
			)
			(justify right)
		)
	)
	(hierarchical_label "USB{USB}"
		(shape input)
		(at 133.35 156.21 180)
		(effects
			(font
				(size 1.27 1.27)
			)
			(justify right)
		)
	)
	(hierarchical_label "PCIe_{x1}{PCIe}"
		(shape input)
		(at 132.08 77.47 180)
		(effects
			(font
				(size 1.27 1.27)
			)
			(justify right)
		)
	)
	(hierarchical_label "~{CLKREQ}"
		(shape output)
		(at 132.08 85.09 180)
		(effects
			(font
				(size 1.27 1.27)
			)
			(justify right)
		)
	)
	(symbol
		(lib_id "antmicropower:GND")
		(at 247.65 83.82 0)
		(unit 1)
		(exclude_from_sim no)
		(in_bom yes)
		(on_board yes)
		(dnp no)
		(property "Reference" "#PWR0181"
			(at 247.65 90.17 0)
			(effects
				(font
					(size 1.27 1.27)
				)
				(hide yes)
			)
		)
		(property "Value" "GND"
			(at 247.65 87.63 0)
			(effects
				(font
					(size 1.27 1.27)
				)
			)
		)
		(property "Footprint" ""
			(at 247.65 83.82 0)
			(effects
				(font
					(size 1.27 1.27)
				)
				(hide yes)
			)
		)
		(property "Datasheet" ""
			(at 247.65 83.82 0)
			(effects
				(font
					(size 1.27 1.27)
				)
				(hide yes)
			)
		)
		(property "Description" ""
			(at 247.65 83.82 0)
			(effects
				(font
					(size 1.27 1.27)
				)
				(hide yes)
			)
		)
		(property "Author" "Antmicro"
			(at 256.54 91.44 0)
			(effects
				(font
					(size 1.27 1.27)
					(thickness 0.15)
				)
				(justify left bottom)
				(hide yes)
			)
		)
		(property "License" "Apache-2.0"
			(at 256.54 93.98 0)
			(effects
				(font
					(size 1.27 1.27)
					(thickness 0.15)
				)
				(justify left bottom)
				(hide yes)
			)
		)
		(pin "1"
		)
		(instances
			(project "com-express-7-baseboard"
				(path ""
					(reference "#PWR0181")
					(unit 1)
				)
			)
		)
	)
	(symbol
		(lib_id "antmicroResistors0402:R_220R_0402")
		(at 234.95 158.75 90)
		(unit 1)
		(exclude_from_sim no)
		(in_bom yes)
		(on_board yes)
		(dnp no)
		(property "Reference" "R138"
			(at 236.22 154.94 90)
			(effects
				(font
					(size 1.27 1.27)
					(thickness 0.15)
				)
				(justify right)
			)
		)
		(property "Value" "R_220R_0402"
			(at 247.65 138.43 0)
			(effects
				(font
					(size 1.27 1.27)
					(thickness 0.15)
				)
				(justify left bottom)
				(hide yes)
			)
		)
		(property "Footprint" "antmicro-footprints:R_0402_1005Metric"
			(at 250.19 138.43 0)
			(effects
				(font
					(size 1.27 1.27)
					(thickness 0.15)
				)
				(justify left bottom)
				(hide yes)
			)
		)
		(property "Datasheet" "https://www.bourns.com/docs/product-datasheets/cr.pdf"
			(at 252.73 138.43 0)
			(effects
				(font
					(size 1.27 1.27)
					(thickness 0.15)
				)
				(justify left bottom)
				(hide yes)
			)
		)
		(property "Description" ""
			(at 234.95 158.75 0)
			(effects
				(font
					(size 1.27 1.27)
				)
				(hide yes)
			)
		)
		(property "MPN" "CR0402-FX-2200GLF"
			(at 255.27 138.43 0)
			(effects
				(font
					(size 1.27 1.27)
					(thickness 0.15)
				)
				(justify left bottom)
				(hide yes)
			)
		)
		(property "Manufacturer" "Bourns"
			(at 257.81 138.43 0)
			(effects
				(font
					(size 1.27 1.27)
					(thickness 0.15)
				)
				(justify left bottom)
				(hide yes)
			)
		)
		(property "License" "Apache-2.0"
			(at 260.35 138.43 0)
			(effects
				(font
					(size 1.27 1.27)
					(thickness 0.15)
				)
				(justify left bottom)
				(hide yes)
			)
		)
		(property "Val" "220R"
			(at 236.22 157.48 90)
			(effects
				(font
					(size 1.27 1.27)
					(thickness 0.15)
				)
				(justify right)
			)
		)
		(property "Tolerance" "1%"
			(at 245.11 138.43 0)
			(effects
				(font
					(size 1.27 1.27)
				)
				(justify left bottom)
				(hide yes)
			)
		)
		(property "Author" "Antmicro"
			(at 262.89 138.43 0)
			(effects
				(font
					(size 1.27 1.27)
					(thickness 0.15)
				)
				(justify left bottom)
				(hide yes)
			)
		)
		(property "Public" "False"
			(at 265.43 138.43 0)
			(effects
				(font
					(size 1.27 1.27)
				)
				(justify left bottom)
				(hide yes)
			)
		)
		(pin "1"
		)
		(pin "2"
		)
		(instances
			(project "com-express-7-baseboard"
				(path ""
					(reference "R138")
					(unit 1)
				)
			)
		)
	)
	(symbol
		(lib_id "antmicroPciConnectors:Bus_M.2_2199230-2")
		(at 182.88 82.55 0)
		(unit 1)
		(exclude_from_sim no)
		(in_bom yes)
		(on_board yes)
		(dnp no)
		(fields_autoplaced yes)
		(property "Reference" "J100"
			(at 198.12 74.93 0)
			(effects
				(font
					(size 1.27 1.27)
					(thickness 0.15)
				)
			)
		)
		(property "Value" "Bus_M.2_2199230-2"
			(at 198.12 76.2 0)
			(effects
				(font
					(size 1.27 1.27)
					(thickness 0.15)
				)
				(hide yes)
			)
		)
		(property "Footprint" "antmicro-footprints:Bus_M.2_Socket_Key_E_TE_2199230-6"
			(at 228.6 88.9 0)
			(effects
				(font
					(size 1.27 1.27)
					(thickness 0.15)
				)
				(justify left bottom)
				(hide yes)
			)
		)
		(property "Datasheet" "https://eu.mouser.com/datasheet/2/418/9/ENG_DS_1_1773702_1NGFFQRG_EN_0214_1_1773702_1NGFF_-3328593.pdf"
			(at 228.6 91.44 0)
			(effects
				(font
					(size 1.27 1.27)
					(thickness 0.15)
				)
				(justify left bottom)
				(hide yes)
			)
		)
		(property "Description" ""
			(at 182.88 82.55 0)
			(effects
				(font
					(size 1.27 1.27)
				)
				(hide yes)
			)
		)
		(property "MPN" "2199230-2"
			(at 198.12 77.47 0)
			(effects
				(font
					(size 1.27 1.27)
					(thickness 0.15)
				)
			)
		)
		(property "Manufacturer" "TE Connectivity"
			(at 228.6 96.52 0)
			(effects
				(font
					(size 1.27 1.27)
					(thickness 0.15)
				)
				(justify left bottom)
				(hide yes)
			)
		)
		(property "Author" "Antmicro"
			(at 228.6 99.06 0)
			(effects
				(font
					(size 1.27 1.27)
					(thickness 0.15)
				)
				(justify left bottom)
				(hide yes)
			)
		)
		(property "License" "Apache-2.0"
			(at 228.6 101.6 0)
			(effects
				(font
					(size 1.27 1.27)
					(thickness 0.15)
				)
				(justify left bottom)
				(hide yes)
			)
		)
		(pin "50"
		)
		(pin "58"
		)
		(pin "70"
		)
		(pin "40"
		)
		(pin "39"
		)
		(pin "18"
		)
		(pin "57"
		)
		(pin "52"
		)
		(pin "34"
		)
		(pin "33"
		)
		(pin "12"
		)
		(pin "11"
		)
		(pin "10"
		)
		(pin "1"
		)
		(pin "74"
		)
		(pin "6"
		)
		(pin "16"
		)
		(pin "62"
		)
		(pin "66"
		)
		(pin "4"
		)
		(pin "15"
		)
		(pin "61"
		)
		(pin "3"
		)
		(pin "9"
		)
		(pin "20"
		)
		(pin "45"
		)
		(pin "60"
		)
		(pin "46"
		)
		(pin "36"
		)
		(pin "73"
		)
		(pin "14"
		)
		(pin "19"
		)
		(pin "72"
		)
		(pin "32"
		)
		(pin "22"
		)
		(pin "49"
		)
		(pin "75"
		)
		(pin "13"
		)
		(pin "51"
		)
		(pin "21"
		)
		(pin "71"
		)
		(pin "48"
		)
		(pin "68"
		)
		(pin "17"
		)
		(pin "23"
		)
		(pin "2"
		)
		(pin "53"
		)
		(pin "59"
		)
		(pin "38"
		)
		(pin "35"
		)
		(pin "7"
		)
		(pin "55"
		)
		(pin "5"
		)
		(pin "56"
		)
		(pin "41"
		)
		(pin "43"
		)
		(pin "42"
		)
		(pin "44"
		)
		(pin "8"
		)
		(pin "MP"
		)
		(pin "64"
		)
		(pin "69"
		)
		(pin "65"
		)
		(pin "47"
		)
		(pin "54"
		)
		(pin "37"
		)
		(pin "67"
		)
		(pin "63"
		)
		(instances
			(project "com-express-7-baseboard"
				(path ""
					(reference "J100")
					(unit 1)
				)
			)
		)
	)
	(symbol
		(lib_id "antmicroResistors0402:R_220R_0402")
		(at 247.65 158.75 90)
		(unit 1)
		(exclude_from_sim no)
		(in_bom yes)
		(on_board yes)
		(dnp no)
		(property "Reference" "R139"
			(at 248.92 154.94 90)
			(effects
				(font
					(size 1.27 1.27)
					(thickness 0.15)
				)
				(justify right)
			)
		)
		(property "Value" "R_220R_0402"
			(at 260.35 138.43 0)
			(effects
				(font
					(size 1.27 1.27)
					(thickness 0.15)
				)
				(justify left bottom)
				(hide yes)
			)
		)
		(property "Footprint" "antmicro-footprints:R_0402_1005Metric"
			(at 262.89 138.43 0)
			(effects
				(font
					(size 1.27 1.27)
					(thickness 0.15)
				)
				(justify left bottom)
				(hide yes)
			)
		)
		(property "Datasheet" "https://www.bourns.com/docs/product-datasheets/cr.pdf"
			(at 265.43 138.43 0)
			(effects
				(font
					(size 1.27 1.27)
					(thickness 0.15)
				)
				(justify left bottom)
				(hide yes)
			)
		)
		(property "Description" ""
			(at 247.65 158.75 0)
			(effects
				(font
					(size 1.27 1.27)
				)
				(hide yes)
			)
		)
		(property "MPN" "CR0402-FX-2200GLF"
			(at 267.97 138.43 0)
			(effects
				(font
					(size 1.27 1.27)
					(thickness 0.15)
				)
				(justify left bottom)
				(hide yes)
			)
		)
		(property "Manufacturer" "Bourns"
			(at 270.51 138.43 0)
			(effects
				(font
					(size 1.27 1.27)
					(thickness 0.15)
				)
				(justify left bottom)
				(hide yes)
			)
		)
		(property "License" "Apache-2.0"
			(at 273.05 138.43 0)
			(effects
				(font
					(size 1.27 1.27)
					(thickness 0.15)
				)
				(justify left bottom)
				(hide yes)
			)
		)
		(property "Val" "220R"
			(at 248.92 157.48 90)
			(effects
				(font
					(size 1.27 1.27)
					(thickness 0.15)
				)
				(justify right)
			)
		)
		(property "Tolerance" "1%"
			(at 257.81 138.43 0)
			(effects
				(font
					(size 1.27 1.27)
				)
				(justify left bottom)
				(hide yes)
			)
		)
		(property "Author" "Antmicro"
			(at 275.59 138.43 0)
			(effects
				(font
					(size 1.27 1.27)
					(thickness 0.15)
				)
				(justify left bottom)
				(hide yes)
			)
		)
		(property "Public" "False"
			(at 278.13 138.43 0)
			(effects
				(font
					(size 1.27 1.27)
				)
				(justify left bottom)
				(hide yes)
			)
		)
		(pin "1"
		)
		(pin "2"
		)
		(instances
			(project "com-express-7-baseboard"
				(path ""
					(reference "R139")
					(unit 1)
				)
			)
		)
	)
	(symbol
		(lib_id "antmicropower:GND")
		(at 238.76 83.82 0)
		(unit 1)
		(exclude_from_sim no)
		(in_bom yes)
		(on_board yes)
		(dnp no)
		(property "Reference" "#PWR0179"
			(at 238.76 90.17 0)
			(effects
				(font
					(size 1.27 1.27)
				)
				(hide yes)
			)
		)
		(property "Value" "GND"
			(at 238.76 87.63 0)
			(effects
				(font
					(size 1.27 1.27)
				)
			)
		)
		(property "Footprint" ""
			(at 238.76 83.82 0)
			(effects
				(font
					(size 1.27 1.27)
				)
				(hide yes)
			)
		)
		(property "Datasheet" ""
			(at 238.76 83.82 0)
			(effects
				(font
					(size 1.27 1.27)
				)
				(hide yes)
			)
		)
		(property "Description" ""
			(at 238.76 83.82 0)
			(effects
				(font
					(size 1.27 1.27)
				)
				(hide yes)
			)
		)
		(property "Author" "Antmicro"
			(at 247.65 91.44 0)
			(effects
				(font
					(size 1.27 1.27)
					(thickness 0.15)
				)
				(justify left bottom)
				(hide yes)
			)
		)
		(property "License" "Apache-2.0"
			(at 247.65 93.98 0)
			(effects
				(font
					(size 1.27 1.27)
					(thickness 0.15)
				)
				(justify left bottom)
				(hide yes)
			)
		)
		(pin "1"
		)
		(instances
			(project "com-express-7-baseboard"
				(path ""
					(reference "#PWR0179")
					(unit 1)
				)
			)
		)
	)
	(symbol
		(lib_id "antmicropower:GND")
		(at 248.92 228.6 0)
		(unit 1)
		(exclude_from_sim no)
		(in_bom yes)
		(on_board yes)
		(dnp no)
		(fields_autoplaced yes)
		(property "Reference" "#PWR0183"
			(at 248.92 234.95 0)
			(effects
				(font
					(size 1.27 1.27)
				)
				(hide yes)
			)
		)
		(property "Value" "GND"
			(at 248.92 233.68 0)
			(effects
				(font
					(size 1.27 1.27)
				)
			)
		)
		(property "Footprint" ""
			(at 248.92 228.6 0)
			(effects
				(font
					(size 1.27 1.27)
				)
				(hide yes)
			)
		)
		(property "Datasheet" ""
			(at 248.92 228.6 0)
			(effects
				(font
					(size 1.27 1.27)
				)
				(hide yes)
			)
		)
		(property "Description" ""
			(at 248.92 228.6 0)
			(effects
				(font
					(size 1.27 1.27)
				)
				(hide yes)
			)
		)
		(property "Author" "Antmicro"
			(at 257.81 236.22 0)
			(effects
				(font
					(size 1.27 1.27)
					(thickness 0.15)
				)
				(justify left bottom)
				(hide yes)
			)
		)
		(property "License" "Apache-2.0"
			(at 257.81 238.76 0)
			(effects
				(font
					(size 1.27 1.27)
					(thickness 0.15)
				)
				(justify left bottom)
				(hide yes)
			)
		)
		(pin "1"
		)
		(instances
			(project "com-express-7-baseboard"
				(path ""
					(reference "#PWR0183")
					(unit 1)
				)
			)
		)
	)
	(symbol
		(lib_id "antmicroMechanicalParts:Spacer_Drill3.7mm_H2.5mm_9774025151R")
		(at 250.19 227.33 0)
		(mirror x)
		(unit 1)
		(exclude_from_sim no)
		(in_bom yes)
		(on_board yes)
		(dnp no)
		(property "Reference" "H3"
			(at 260.35 226.06 0)
			(effects
				(font
					(size 1.27 1.27)
					(thickness 0.15)
				)
			)
		)
		(property "Value" "Spacer_Drill3.7mm_H2.5mm_9774025151R"
			(at 279.4 228.6 0)
			(effects
				(font
					(size 1.27 1.27)
					(thickness 0.15)
				)
			)
		)
		(property "Footprint" "antmicro-footprints:Spacer_Drill3.7mm_H2.5mm_9774025151R"
			(at 273.05 219.71 0)
			(effects
				(font
					(size 1.27 1.27)
					(thickness 0.15)
				)
				(justify left bottom)
				(hide yes)
			)
		)
		(property "Datasheet" "https://www.we-online.com/components/products/datasheet/9774025151R.pdf"
			(at 273.05 217.17 0)
			(effects
				(font
					(size 1.27 1.27)
					(thickness 0.15)
				)
				(justify left bottom)
				(hide yes)
			)
		)
		(property "Description" ""
			(at 250.19 227.33 0)
			(effects
				(font
					(size 1.27 1.27)
				)
				(hide yes)
			)
		)
		(property "Manufacturer" "Würth Elektronik"
			(at 273.05 214.63 0)
			(effects
				(font
					(size 1.27 1.27)
					(thickness 0.15)
				)
				(justify left bottom)
				(hide yes)
			)
		)
		(property "MPN" "9774025151R"
			(at 273.05 212.09 0)
			(effects
				(font
					(size 1.27 1.27)
					(thickness 0.15)
				)
				(justify left bottom)
				(hide yes)
			)
		)
		(property "Author" "Antmicro"
			(at 273.05 209.55 0)
			(effects
				(font
					(size 1.27 1.27)
					(thickness 0.15)
				)
				(justify left bottom)
				(hide yes)
			)
		)
		(property "License" "Apache-2.0"
			(at 273.05 207.01 0)
			(effects
				(font
					(size 1.27 1.27)
					(thickness 0.15)
				)
				(justify left bottom)
				(hide yes)
			)
		)
		(property "Public" "False"
			(at 273.05 214.63 0)
			(effects
				(font
					(size 1.27 1.27)
				)
				(justify left bottom)
				(hide yes)
			)
		)
		(pin "1"
		)
		(instances
			(project "com-express-7-baseboard"
				(path ""
					(reference "H3")
					(unit 1)
				)
			)
		)
	)
	(symbol
		(lib_id "antmicroCapacitors0603:C_22u_16V_0603")
		(at 229.87 82.55 90)
		(unit 1)
		(exclude_from_sim no)
		(in_bom yes)
		(on_board yes)
		(dnp no)
		(fields_autoplaced yes)
		(property "Reference" "C80"
			(at 232.41 78.7336 90)
			(effects
				(font
					(size 1.27 1.27)
					(thickness 0.15)
				)
				(justify right)
			)
		)
		(property "Value" "C_22u_16V_0603"
			(at 240.03 62.23 0)
			(effects
				(font
					(size 1.27 1.27)
					(thickness 0.15)
				)
				(justify left bottom)
				(hide yes)
			)
		)
		(property "Footprint" "antmicro-footprints:C_0603_1608Metric"
			(at 242.57 62.23 0)
			(effects
				(font
					(size 1.27 1.27)
					(thickness 0.15)
				)
				(justify left bottom)
				(hide yes)
			)
		)
		(property "Datasheet" "https://product.samsungsem.com/mlcc/CL10A226MO7JZN.do"
			(at 245.11 62.23 0)
			(effects
				(font
					(size 1.27 1.27)
					(thickness 0.15)
				)
				(justify left bottom)
				(hide yes)
			)
		)
		(property "Description" ""
			(at 229.87 82.55 0)
			(effects
				(font
					(size 1.27 1.27)
				)
				(hide yes)
			)
		)
		(property "MPN" "CL10A226MO7JZNC"
			(at 247.65 62.23 0)
			(effects
				(font
					(size 1.27 1.27)
					(thickness 0.15)
				)
				(justify left bottom)
				(hide yes)
			)
		)
		(property "Manufacturer" "Samsung Electro-Mechanics"
			(at 250.19 62.23 0)
			(effects
				(font
					(size 1.27 1.27)
					(thickness 0.15)
				)
				(justify left bottom)
				(hide yes)
			)
		)
		(property "License" "Apache-2.0"
			(at 252.73 62.23 0)
			(effects
				(font
					(size 1.27 1.27)
					(thickness 0.15)
				)
				(justify left bottom)
				(hide yes)
			)
		)
		(property "Author" "Antmicro"
			(at 255.27 62.23 0)
			(effects
				(font
					(size 1.27 1.27)
					(thickness 0.15)
				)
				(justify left bottom)
				(hide yes)
			)
		)
		(property "Val" "22u"
			(at 232.41 81.2736 90)
			(effects
				(font
					(size 1.27 1.27)
					(thickness 0.15)
				)
				(justify right)
			)
		)
		(property "Voltage" "16V"
			(at 257.81 62.23 0)
			(effects
				(font
					(size 1.27 1.27)
				)
				(justify left bottom)
				(hide yes)
			)
		)
		(property "Dielectric" ""
			(at 260.35 62.23 0)
			(effects
				(font
					(size 1.27 1.27)
				)
				(justify left bottom)
				(hide yes)
			)
		)
		(property "Public" "False"
			(at 262.89 62.23 0)
			(effects
				(font
					(size 1.27 1.27)
				)
				(justify left bottom)
				(hide yes)
			)
		)
		(pin "1"
		)
		(pin "2"
		)
		(instances
			(project "com-express-7-baseboard"
				(path ""
					(reference "C80")
					(unit 1)
				)
			)
		)
	)
	(symbol
		(lib_id "antmicroLEDIndicationDiscrete:LED_G_0603_LTST-C190GKT")
		(at 234.95 165.1 90)
		(unit 1)
		(exclude_from_sim no)
		(in_bom yes)
		(on_board yes)
		(dnp no)
		(fields_autoplaced yes)
		(property "Reference" "D15"
			(at 231.14 161.29 90)
			(effects
				(font
					(size 1.27 1.27)
				)
				(justify left)
			)
		)
		(property "Value" "LED_G_0603_LTST-C190GKT"
			(at 242.57 142.24 0)
			(effects
				(font
					(size 1.27 1.27)
					(thickness 0.15)
				)
				(justify left bottom)
				(hide yes)
			)
		)
		(property "Footprint" "antmicro-footprints:LED_0603_1608Metric_G"
			(at 245.11 142.24 0)
			(effects
				(font
					(size 1.27 1.27)
					(thickness 0.15)
				)
				(justify left bottom)
				(hide yes)
			)
		)
		(property "Datasheet" "https://media.digikey.com/pdf/Data%20Sheets/Lite-On%20PDFs/LTST-C190GKT.pdf"
			(at 247.65 142.24 0)
			(effects
				(font
					(size 1.27 1.27)
					(thickness 0.15)
				)
				(justify left bottom)
				(hide yes)
			)
		)
		(property "Description" ""
			(at 234.95 165.1 0)
			(effects
				(font
					(size 1.27 1.27)
				)
				(hide yes)
			)
		)
		(property "MPN" "LTST-C190GKT"
			(at 238.125 171.45 0)
			(effects
				(font
					(size 1.27 1.27)
					(thickness 0.15)
				)
				(justify left)
				(hide yes)
			)
		)
		(property "Manufacturer" "Lite-On"
			(at 252.73 142.24 0)
			(effects
				(font
					(size 1.27 1.27)
					(thickness 0.15)
				)
				(justify left bottom)
				(hide yes)
			)
		)
		(property "Author" "Antmicro"
			(at 255.27 142.24 0)
			(effects
				(font
					(size 1.27 1.27)
					(thickness 0.15)
				)
				(justify left bottom)
				(hide yes)
			)
		)
		(property "License" "Apache-2.0"
			(at 257.81 142.24 0)
			(effects
				(font
					(size 1.27 1.27)
					(thickness 0.15)
				)
				(justify left bottom)
				(hide yes)
			)
		)
		(property "Public" "False"
			(at 252.73 144.78 0)
			(effects
				(font
					(size 1.27 1.27)
				)
				(justify left bottom)
				(hide yes)
			)
		)
		(property "Color" "Green"
			(at 231.14 163.83 90)
			(effects
				(font
					(size 1.27 1.27)
				)
				(justify left)
			)
		)
		(pin "1"
		)
		(pin "2"
		)
		(instances
			(project "com-express-7-baseboard"
				(path ""
					(reference "D15")
					(unit 1)
				)
			)
		)
	)
	(symbol
		(lib_id "antmicroResistors0402:R_0R_0402")
		(at 154.94 161.29 0)
		(unit 1)
		(exclude_from_sim no)
		(in_bom yes)
		(on_board yes)
		(dnp no)
		(property "Reference" "R133"
			(at 152.4 160.02 0)
			(effects
				(font
					(size 1.27 1.27)
					(thickness 0.15)
				)
			)
		)
		(property "Value" "R_0R_0402"
			(at 175.26 173.99 0)
			(effects
				(font
					(size 1.27 1.27)
					(thickness 0.15)
				)
				(justify left bottom)
				(hide yes)
			)
		)
		(property "Footprint" "antmicro-footprints:R_0402_1005Metric"
			(at 175.26 176.53 0)
			(effects
				(font
					(size 1.27 1.27)
					(thickness 0.15)
				)
				(justify left bottom)
				(hide yes)
			)
		)
		(property "Datasheet" "https://industrial.panasonic.com/cdbs/www-data/pdf/RDA0000/AOA0000C301.pdf"
			(at 175.26 179.07 0)
			(effects
				(font
					(size 1.27 1.27)
					(thickness 0.15)
				)
				(justify left bottom)
				(hide yes)
			)
		)
		(property "Description" ""
			(at 154.94 161.29 0)
			(effects
				(font
					(size 1.27 1.27)
				)
				(hide yes)
			)
		)
		(property "MPN" "ERJ2GE0R00X"
			(at 175.26 181.61 0)
			(effects
				(font
					(size 1.27 1.27)
					(thickness 0.15)
				)
				(justify left bottom)
				(hide yes)
			)
		)
		(property "Manufacturer" "Panasonic"
			(at 175.26 184.15 0)
			(effects
				(font
					(size 1.27 1.27)
					(thickness 0.15)
				)
				(justify left bottom)
				(hide yes)
			)
		)
		(property "License" "Apache-2.0"
			(at 175.26 186.69 0)
			(effects
				(font
					(size 1.27 1.27)
					(thickness 0.15)
				)
				(justify left bottom)
				(hide yes)
			)
		)
		(property "Val" "0R"
			(at 161.29 160.02 0)
			(effects
				(font
					(size 1.27 1.27)
					(thickness 0.15)
				)
			)
		)
		(property "Tolerance" "~"
			(at 175.26 171.45 0)
			(effects
				(font
					(size 1.27 1.27)
				)
				(justify left bottom)
				(hide yes)
			)
		)
		(property "Current" "1A"
			(at 157.48 158.115 0)
			(effects
				(font
					(size 1.27 1.27)
					(thickness 0.15)
				)
				(hide yes)
			)
		)
		(property "Author" "Antmicro"
			(at 175.26 189.23 0)
			(effects
				(font
					(size 1.27 1.27)
					(thickness 0.15)
				)
				(justify left bottom)
				(hide yes)
			)
		)
		(property "Public" "False"
			(at 175.26 191.77 0)
			(effects
				(font
					(size 1.27 1.27)
				)
				(justify left bottom)
				(hide yes)
			)
		)
		(pin "1"
		)
		(pin "2"
		)
		(instances
			(project "com-express-7-baseboard"
				(path ""
					(reference "R133")
					(unit 1)
				)
			)
		)
	)
	(symbol
		(lib_id "antmicropower:+3V3")
		(at 234.95 153.67 0)
		(unit 1)
		(exclude_from_sim no)
		(in_bom yes)
		(on_board yes)
		(dnp no)
		(property "Reference" "#PWR0178"
			(at 234.95 157.48 0)
			(effects
				(font
					(size 1.27 1.27)
				)
				(hide yes)
			)
		)
		(property "Value" "+3V3"
			(at 234.95 149.86 0)
			(effects
				(font
					(size 1.27 1.27)
				)
			)
		)
		(property "Footprint" ""
			(at 234.95 153.67 0)
			(effects
				(font
					(size 1.27 1.27)
				)
				(hide yes)
			)
		)
		(property "Datasheet" ""
			(at 234.95 153.67 0)
			(effects
				(font
					(size 1.27 1.27)
				)
				(hide yes)
			)
		)
		(property "Description" ""
			(at 234.95 153.67 0)
			(effects
				(font
					(size 1.27 1.27)
				)
				(hide yes)
			)
		)
		(property "Author" "Antmicro"
			(at 250.19 156.21 0)
			(effects
				(font
					(size 1.27 1.27)
					(thickness 0.15)
				)
				(justify left bottom)
				(hide yes)
			)
		)
		(property "License" "Apache-2.0"
			(at 250.19 158.75 0)
			(effects
				(font
					(size 1.27 1.27)
					(thickness 0.15)
				)
				(justify left bottom)
				(hide yes)
			)
		)
		(pin "1"
		)
		(instances
			(project "com-express-7-baseboard"
				(path ""
					(reference "#PWR0178")
					(unit 1)
				)
			)
		)
	)
	(symbol
		(lib_id "antmicropower:GND")
		(at 218.44 187.96 0)
		(unit 1)
		(exclude_from_sim no)
		(in_bom yes)
		(on_board yes)
		(dnp no)
		(fields_autoplaced yes)
		(property "Reference" "#PWR0175"
			(at 218.44 194.31 0)
			(effects
				(font
					(size 1.27 1.27)
				)
				(hide yes)
			)
		)
		(property "Value" "GND"
			(at 218.44 193.04 0)
			(effects
				(font
					(size 1.27 1.27)
				)
			)
		)
		(property "Footprint" ""
			(at 218.44 187.96 0)
			(effects
				(font
					(size 1.27 1.27)
				)
				(hide yes)
			)
		)
		(property "Datasheet" ""
			(at 218.44 187.96 0)
			(effects
				(font
					(size 1.27 1.27)
				)
				(hide yes)
			)
		)
		(property "Description" ""
			(at 218.44 187.96 0)
			(effects
				(font
					(size 1.27 1.27)
				)
				(hide yes)
			)
		)
		(property "Author" "Antmicro"
			(at 227.33 195.58 0)
			(effects
				(font
					(size 1.27 1.27)
					(thickness 0.15)
				)
				(justify left bottom)
				(hide yes)
			)
		)
		(property "License" "Apache-2.0"
			(at 227.33 198.12 0)
			(effects
				(font
					(size 1.27 1.27)
					(thickness 0.15)
				)
				(justify left bottom)
				(hide yes)
			)
		)
		(pin "1"
		)
		(instances
			(project "com-express-7-baseboard"
				(path ""
					(reference "#PWR0175")
					(unit 1)
				)
			)
		)
	)
	(symbol
		(lib_id "antmicroCapacitors0603:C_22u_16V_0603")
		(at 220.98 82.55 90)
		(unit 1)
		(exclude_from_sim no)
		(in_bom yes)
		(on_board yes)
		(dnp no)
		(fields_autoplaced yes)
		(property "Reference" "C79"
			(at 223.52 78.7336 90)
			(effects
				(font
					(size 1.27 1.27)
					(thickness 0.15)
				)
				(justify right)
			)
		)
		(property "Value" "C_22u_16V_0603"
			(at 231.14 62.23 0)
			(effects
				(font
					(size 1.27 1.27)
					(thickness 0.15)
				)
				(justify left bottom)
				(hide yes)
			)
		)
		(property "Footprint" "antmicro-footprints:C_0603_1608Metric"
			(at 233.68 62.23 0)
			(effects
				(font
					(size 1.27 1.27)
					(thickness 0.15)
				)
				(justify left bottom)
				(hide yes)
			)
		)
		(property "Datasheet" "https://product.samsungsem.com/mlcc/CL10A226MO7JZN.do"
			(at 236.22 62.23 0)
			(effects
				(font
					(size 1.27 1.27)
					(thickness 0.15)
				)
				(justify left bottom)
				(hide yes)
			)
		)
		(property "Description" ""
			(at 220.98 82.55 0)
			(effects
				(font
					(size 1.27 1.27)
				)
				(hide yes)
			)
		)
		(property "MPN" "CL10A226MO7JZNC"
			(at 238.76 62.23 0)
			(effects
				(font
					(size 1.27 1.27)
					(thickness 0.15)
				)
				(justify left bottom)
				(hide yes)
			)
		)
		(property "Manufacturer" "Samsung Electro-Mechanics"
			(at 241.3 62.23 0)
			(effects
				(font
					(size 1.27 1.27)
					(thickness 0.15)
				)
				(justify left bottom)
				(hide yes)
			)
		)
		(property "License" "Apache-2.0"
			(at 243.84 62.23 0)
			(effects
				(font
					(size 1.27 1.27)
					(thickness 0.15)
				)
				(justify left bottom)
				(hide yes)
			)
		)
		(property "Author" "Antmicro"
			(at 246.38 62.23 0)
			(effects
				(font
					(size 1.27 1.27)
					(thickness 0.15)
				)
				(justify left bottom)
				(hide yes)
			)
		)
		(property "Val" "22u"
			(at 223.52 81.2736 90)
			(effects
				(font
					(size 1.27 1.27)
					(thickness 0.15)
				)
				(justify right)
			)
		)
		(property "Voltage" "16V"
			(at 248.92 62.23 0)
			(effects
				(font
					(size 1.27 1.27)
				)
				(justify left bottom)
				(hide yes)
			)
		)
		(property "Dielectric" ""
			(at 251.46 62.23 0)
			(effects
				(font
					(size 1.27 1.27)
				)
				(justify left bottom)
				(hide yes)
			)
		)
		(property "Public" "False"
			(at 254 62.23 0)
			(effects
				(font
					(size 1.27 1.27)
				)
				(justify left bottom)
				(hide yes)
			)
		)
		(pin "1"
		)
		(pin "2"
		)
		(instances
			(project "com-express-7-baseboard"
				(path ""
					(reference "C79")
					(unit 1)
				)
			)
		)
	)
	(symbol
		(lib_id "antmicroLEDIndicationDiscrete:LED_G_0603_LTST-C190GKT")
		(at 247.65 165.1 90)
		(unit 1)
		(exclude_from_sim no)
		(in_bom yes)
		(on_board yes)
		(dnp no)
		(property "Reference" "D16"
			(at 243.84 161.29 90)
			(effects
				(font
					(size 1.27 1.27)
				)
				(justify left)
			)
		)
		(property "Value" "LED_G_0603_LTST-C190GKT"
			(at 255.27 142.24 0)
			(effects
				(font
					(size 1.27 1.27)
					(thickness 0.15)
				)
				(justify left bottom)
				(hide yes)
			)
		)
		(property "Footprint" "antmicro-footprints:LED_0603_1608Metric_G"
			(at 257.81 142.24 0)
			(effects
				(font
					(size 1.27 1.27)
					(thickness 0.15)
				)
				(justify left bottom)
				(hide yes)
			)
		)
		(property "Datasheet" "https://media.digikey.com/pdf/Data%20Sheets/Lite-On%20PDFs/LTST-C190GKT.pdf"
			(at 260.35 142.24 0)
			(effects
				(font
					(size 1.27 1.27)
					(thickness 0.15)
				)
				(justify left bottom)
				(hide yes)
			)
		)
		(property "Description" ""
			(at 247.65 165.1 0)
			(effects
				(font
					(size 1.27 1.27)
				)
				(hide yes)
			)
		)
		(property "MPN" "LTST-C190GKT"
			(at 250.825 171.45 0)
			(effects
				(font
					(size 1.27 1.27)
					(thickness 0.15)
				)
				(justify left)
				(hide yes)
			)
		)
		(property "Manufacturer" "Lite-On"
			(at 265.43 142.24 0)
			(effects
				(font
					(size 1.27 1.27)
					(thickness 0.15)
				)
				(justify left bottom)
				(hide yes)
			)
		)
		(property "Author" "Antmicro"
			(at 267.97 142.24 0)
			(effects
				(font
					(size 1.27 1.27)
					(thickness 0.15)
				)
				(justify left bottom)
				(hide yes)
			)
		)
		(property "License" "Apache-2.0"
			(at 270.51 142.24 0)
			(effects
				(font
					(size 1.27 1.27)
					(thickness 0.15)
				)
				(justify left bottom)
				(hide yes)
			)
		)
		(property "Public" "False"
			(at 265.43 144.78 0)
			(effects
				(font
					(size 1.27 1.27)
				)
				(justify left bottom)
				(hide yes)
			)
		)
		(property "Color" "Green"
			(at 243.84 163.83 90)
			(effects
				(font
					(size 1.27 1.27)
				)
				(justify left)
			)
		)
		(pin "1"
		)
		(pin "2"
		)
		(instances
			(project "com-express-7-baseboard"
				(path ""
					(reference "D16")
					(unit 1)
				)
			)
		)
	)
	(symbol
		(lib_id "antmicropower:GND")
		(at 220.98 83.82 0)
		(unit 1)
		(exclude_from_sim no)
		(in_bom yes)
		(on_board yes)
		(dnp no)
		(property "Reference" "#PWR0176"
			(at 220.98 90.17 0)
			(effects
				(font
					(size 1.27 1.27)
				)
				(hide yes)
			)
		)
		(property "Value" "GND"
			(at 220.98 87.63 0)
			(effects
				(font
					(size 1.27 1.27)
				)
			)
		)
		(property "Footprint" ""
			(at 220.98 83.82 0)
			(effects
				(font
					(size 1.27 1.27)
				)
				(hide yes)
			)
		)
		(property "Datasheet" ""
			(at 220.98 83.82 0)
			(effects
				(font
					(size 1.27 1.27)
				)
				(hide yes)
			)
		)
		(property "Description" ""
			(at 220.98 83.82 0)
			(effects
				(font
					(size 1.27 1.27)
				)
				(hide yes)
			)
		)
		(property "Author" "Antmicro"
			(at 229.87 91.44 0)
			(effects
				(font
					(size 1.27 1.27)
					(thickness 0.15)
				)
				(justify left bottom)
				(hide yes)
			)
		)
		(property "License" "Apache-2.0"
			(at 229.87 93.98 0)
			(effects
				(font
					(size 1.27 1.27)
					(thickness 0.15)
				)
				(justify left bottom)
				(hide yes)
			)
		)
		(pin "1"
		)
		(instances
			(project "com-express-7-baseboard"
				(path ""
					(reference "#PWR0176")
					(unit 1)
				)
			)
		)
	)
	(symbol
		(lib_id "antmicropower:+3V3")
		(at 166.37 73.66 0)
		(unit 1)
		(exclude_from_sim no)
		(in_bom yes)
		(on_board yes)
		(dnp no)
		(fields_autoplaced yes)
		(property "Reference" "#PWR0174"
			(at 166.37 77.47 0)
			(effects
				(font
					(size 1.27 1.27)
				)
				(justify left bottom)
				(hide yes)
			)
		)
		(property "Value" "+3V3"
			(at 166.37 70.104 0)
			(effects
				(font
					(size 1.27 1.27)
				)
				(justify left bottom)
			)
		)
		(property "Footprint" ""
			(at 166.37 73.66 0)
			(effects
				(font
					(size 1.27 1.27)
				)
				(justify left bottom)
				(hide yes)
			)
		)
		(property "Datasheet" ""
			(at 166.37 73.66 0)
			(effects
				(font
					(size 1.27 1.27)
				)
				(justify left bottom)
				(hide yes)
			)
		)
		(property "Description" ""
			(at 166.37 73.66 0)
			(effects
				(font
					(size 1.27 1.27)
				)
				(hide yes)
			)
		)
		(property "Author" "Antmicro"
			(at 181.61 76.2 0)
			(effects
				(font
					(size 1.27 1.27)
					(thickness 0.15)
				)
				(justify left bottom)
				(hide yes)
			)
		)
		(property "License" "Apache-2.0"
			(at 181.61 78.74 0)
			(effects
				(font
					(size 1.27 1.27)
					(thickness 0.15)
				)
				(justify left bottom)
				(hide yes)
			)
		)
		(pin "1"
		)
		(instances
			(project "com-express-7-baseboard"
				(path ""
					(reference "#PWR0174")
					(unit 1)
				)
			)
		)
	)
	(symbol
		(lib_id "antmicropower:+3V3")
		(at 247.65 153.67 0)
		(unit 1)
		(exclude_from_sim no)
		(in_bom yes)
		(on_board yes)
		(dnp no)
		(property "Reference" "#PWR0182"
			(at 247.65 157.48 0)
			(effects
				(font
					(size 1.27 1.27)
				)
				(hide yes)
			)
		)
		(property "Value" "+3V3"
			(at 247.65 149.86 0)
			(effects
				(font
					(size 1.27 1.27)
				)
			)
		)
		(property "Footprint" ""
			(at 247.65 153.67 0)
			(effects
				(font
					(size 1.27 1.27)
				)
				(hide yes)
			)
		)
		(property "Datasheet" ""
			(at 247.65 153.67 0)
			(effects
				(font
					(size 1.27 1.27)
				)
				(hide yes)
			)
		)
		(property "Description" ""
			(at 247.65 153.67 0)
			(effects
				(font
					(size 1.27 1.27)
				)
				(hide yes)
			)
		)
		(property "Author" "Antmicro"
			(at 262.89 156.21 0)
			(effects
				(font
					(size 1.27 1.27)
					(thickness 0.15)
				)
				(justify left bottom)
				(hide yes)
			)
		)
		(property "License" "Apache-2.0"
			(at 262.89 158.75 0)
			(effects
				(font
					(size 1.27 1.27)
					(thickness 0.15)
				)
				(justify left bottom)
				(hide yes)
			)
		)
		(pin "1"
		)
		(instances
			(project "com-express-7-baseboard"
				(path ""
					(reference "#PWR0182")
					(unit 1)
				)
			)
		)
	)
	(symbol
		(lib_id "antmicroCapacitors0603:C_22u_16V_0603")
		(at 247.65 82.55 90)
		(unit 1)
		(exclude_from_sim no)
		(in_bom yes)
		(on_board yes)
		(dnp no)
		(fields_autoplaced yes)
		(property "Reference" "C82"
			(at 250.19 78.7336 90)
			(effects
				(font
					(size 1.27 1.27)
					(thickness 0.15)
				)
				(justify right)
			)
		)
		(property "Value" "C_22u_16V_0603"
			(at 257.81 62.23 0)
			(effects
				(font
					(size 1.27 1.27)
					(thickness 0.15)
				)
				(justify left bottom)
				(hide yes)
			)
		)
		(property "Footprint" "antmicro-footprints:C_0603_1608Metric"
			(at 260.35 62.23 0)
			(effects
				(font
					(size 1.27 1.27)
					(thickness 0.15)
				)
				(justify left bottom)
				(hide yes)
			)
		)
		(property "Datasheet" "https://product.samsungsem.com/mlcc/CL10A226MO7JZN.do"
			(at 262.89 62.23 0)
			(effects
				(font
					(size 1.27 1.27)
					(thickness 0.15)
				)
				(justify left bottom)
				(hide yes)
			)
		)
		(property "Description" ""
			(at 247.65 82.55 0)
			(effects
				(font
					(size 1.27 1.27)
				)
				(hide yes)
			)
		)
		(property "MPN" "CL10A226MO7JZNC"
			(at 265.43 62.23 0)
			(effects
				(font
					(size 1.27 1.27)
					(thickness 0.15)
				)
				(justify left bottom)
				(hide yes)
			)
		)
		(property "Manufacturer" "Samsung Electro-Mechanics"
			(at 267.97 62.23 0)
			(effects
				(font
					(size 1.27 1.27)
					(thickness 0.15)
				)
				(justify left bottom)
				(hide yes)
			)
		)
		(property "License" "Apache-2.0"
			(at 270.51 62.23 0)
			(effects
				(font
					(size 1.27 1.27)
					(thickness 0.15)
				)
				(justify left bottom)
				(hide yes)
			)
		)
		(property "Author" "Antmicro"
			(at 273.05 62.23 0)
			(effects
				(font
					(size 1.27 1.27)
					(thickness 0.15)
				)
				(justify left bottom)
				(hide yes)
			)
		)
		(property "Val" "22u"
			(at 250.19 81.2736 90)
			(effects
				(font
					(size 1.27 1.27)
					(thickness 0.15)
				)
				(justify right)
			)
		)
		(property "Voltage" "16V"
			(at 275.59 62.23 0)
			(effects
				(font
					(size 1.27 1.27)
				)
				(justify left bottom)
				(hide yes)
			)
		)
		(property "Dielectric" ""
			(at 278.13 62.23 0)
			(effects
				(font
					(size 1.27 1.27)
				)
				(justify left bottom)
				(hide yes)
			)
		)
		(property "Public" "False"
			(at 280.67 62.23 0)
			(effects
				(font
					(size 1.27 1.27)
				)
				(justify left bottom)
				(hide yes)
			)
		)
		(pin "1"
		)
		(pin "2"
		)
		(instances
			(project "com-express-7-baseboard"
				(path ""
					(reference "C82")
					(unit 1)
				)
			)
		)
	)
	(symbol
		(lib_id "antmicroResistors0402:R_0R_0402")
		(at 144.78 82.55 0)
		(unit 1)
		(exclude_from_sim no)
		(in_bom yes)
		(on_board yes)
		(dnp no)
		(property "Reference" "R132"
			(at 142.24 81.28 0)
			(effects
				(font
					(size 1.27 1.27)
					(thickness 0.15)
				)
			)
		)
		(property "Value" "R_0R_0402"
			(at 165.1 95.25 0)
			(effects
				(font
					(size 1.27 1.27)
					(thickness 0.15)
				)
				(justify left bottom)
				(hide yes)
			)
		)
		(property "Footprint" "antmicro-footprints:R_0402_1005Metric"
			(at 165.1 97.79 0)
			(effects
				(font
					(size 1.27 1.27)
					(thickness 0.15)
				)
				(justify left bottom)
				(hide yes)
			)
		)
		(property "Datasheet" "https://industrial.panasonic.com/cdbs/www-data/pdf/RDA0000/AOA0000C301.pdf"
			(at 165.1 100.33 0)
			(effects
				(font
					(size 1.27 1.27)
					(thickness 0.15)
				)
				(justify left bottom)
				(hide yes)
			)
		)
		(property "Description" ""
			(at 144.78 82.55 0)
			(effects
				(font
					(size 1.27 1.27)
				)
				(hide yes)
			)
		)
		(property "MPN" "ERJ2GE0R00X"
			(at 165.1 102.87 0)
			(effects
				(font
					(size 1.27 1.27)
					(thickness 0.15)
				)
				(justify left bottom)
				(hide yes)
			)
		)
		(property "Manufacturer" "Panasonic"
			(at 165.1 105.41 0)
			(effects
				(font
					(size 1.27 1.27)
					(thickness 0.15)
				)
				(justify left bottom)
				(hide yes)
			)
		)
		(property "License" "Apache-2.0"
			(at 165.1 107.95 0)
			(effects
				(font
					(size 1.27 1.27)
					(thickness 0.15)
				)
				(justify left bottom)
				(hide yes)
			)
		)
		(property "Author" "Antmicro"
			(at 165.1 110.49 0)
			(effects
				(font
					(size 1.27 1.27)
					(thickness 0.15)
				)
				(justify left bottom)
				(hide yes)
			)
		)
		(property "Val" "0R"
			(at 151.13 81.28 0)
			(effects
				(font
					(size 1.27 1.27)
					(thickness 0.15)
				)
			)
		)
		(property "Tolerance" "~"
			(at 165.1 92.71 0)
			(effects
				(font
					(size 1.27 1.27)
				)
				(justify left bottom)
				(hide yes)
			)
		)
		(property "Current" "1A"
			(at 165.1 113.03 0)
			(effects
				(font
					(size 1.27 1.27)
					(thickness 0.15)
				)
				(justify left bottom)
				(hide yes)
			)
		)
		(property "Public" "False"
			(at 165.1 113.03 0)
			(effects
				(font
					(size 1.27 1.27)
				)
				(justify left bottom)
				(hide yes)
			)
		)
		(pin "1"
		)
		(pin "2"
		)
		(instances
			(project "com-express-7-baseboard"
				(path ""
					(reference "R132")
					(unit 1)
				)
			)
		)
	)
	(symbol
		(lib_id "antmicroResistors0402:R_10k_0402")
		(at 166.37 81.28 90)
		(unit 1)
		(exclude_from_sim no)
		(in_bom yes)
		(on_board yes)
		(dnp yes)
		(fields_autoplaced yes)
		(property "Reference" "R135"
			(at 168.91 76.2 90)
			(effects
				(font
					(size 1.27 1.27)
					(thickness 0.15)
				)
				(justify right)
			)
		)
		(property "Value" "R_10k_0402"
			(at 179.07 60.96 0)
			(effects
				(font
					(size 1.27 1.27)
					(thickness 0.15)
				)
				(justify left bottom)
				(hide yes)
			)
		)
		(property "Footprint" "antmicro-footprints:R_0402_1005Metric"
			(at 181.61 60.96 0)
			(effects
				(font
					(size 1.27 1.27)
					(thickness 0.15)
				)
				(justify left bottom)
				(hide yes)
			)
		)
		(property "Datasheet" "https://www.bourns.com/docs/product-datasheets/cr.pdf"
			(at 184.15 60.96 0)
			(effects
				(font
					(size 1.27 1.27)
					(thickness 0.15)
				)
				(justify left bottom)
				(hide yes)
			)
		)
		(property "Description" ""
			(at 166.37 81.28 0)
			(effects
				(font
					(size 1.27 1.27)
				)
				(hide yes)
			)
		)
		(property "MPN" "CR0402-FX-1002GLF"
			(at 186.69 60.96 0)
			(effects
				(font
					(size 1.27 1.27)
					(thickness 0.15)
				)
				(justify left bottom)
				(hide yes)
			)
		)
		(property "Manufacturer" "Bourns"
			(at 189.23 60.96 0)
			(effects
				(font
					(size 1.27 1.27)
					(thickness 0.15)
				)
				(justify left bottom)
				(hide yes)
			)
		)
		(property "License" "Apache-2.0"
			(at 191.77 60.96 0)
			(effects
				(font
					(size 1.27 1.27)
					(thickness 0.15)
				)
				(justify left bottom)
				(hide yes)
			)
		)
		(property "Author" "Antmicro"
			(at 194.31 60.96 0)
			(effects
				(font
					(size 1.27 1.27)
					(thickness 0.15)
				)
				(justify left bottom)
				(hide yes)
			)
		)
		(property "Val" "10k"
			(at 168.91 78.74 90)
			(effects
				(font
					(size 1.27 1.27)
					(thickness 0.15)
				)
				(justify right)
			)
		)
		(property "Tolerance" "1%"
			(at 176.53 60.96 0)
			(effects
				(font
					(size 1.27 1.27)
				)
				(justify left bottom)
				(hide yes)
			)
		)
		(property "Public" "False"
			(at 196.85 60.96 0)
			(effects
				(font
					(size 1.27 1.27)
				)
				(justify left bottom)
				(hide yes)
			)
		)
		(pin "2"
		)
		(pin "1"
		)
		(instances
			(project "com-express-7-baseboard"
				(path ""
					(reference "R135")
					(unit 1)
				)
			)
		)
	)
	(symbol
		(lib_id "antmicropower:+3V3")
		(at 247.65 72.39 0)
		(unit 1)
		(exclude_from_sim no)
		(in_bom yes)
		(on_board yes)
		(dnp no)
		(property "Reference" "#PWR0180"
			(at 247.65 76.2 0)
			(effects
				(font
					(size 1.27 1.27)
				)
				(hide yes)
			)
		)
		(property "Value" "+3V3"
			(at 247.65 68.58 0)
			(effects
				(font
					(size 1.27 1.27)
				)
			)
		)
		(property "Footprint" ""
			(at 247.65 72.39 0)
			(effects
				(font
					(size 1.27 1.27)
				)
				(hide yes)
			)
		)
		(property "Datasheet" ""
			(at 247.65 72.39 0)
			(effects
				(font
					(size 1.27 1.27)
				)
				(hide yes)
			)
		)
		(property "Description" ""
			(at 247.65 72.39 0)
			(effects
				(font
					(size 1.27 1.27)
				)
				(hide yes)
			)
		)
		(property "Author" "Antmicro"
			(at 262.89 74.93 0)
			(effects
				(font
					(size 1.27 1.27)
					(thickness 0.15)
				)
				(justify left bottom)
				(hide yes)
			)
		)
		(property "License" "Apache-2.0"
			(at 262.89 77.47 0)
			(effects
				(font
					(size 1.27 1.27)
					(thickness 0.15)
				)
				(justify left bottom)
				(hide yes)
			)
		)
		(pin "1"
		)
		(instances
			(project "com-express-7-baseboard"
				(path ""
					(reference "#PWR0180")
					(unit 1)
				)
			)
		)
	)
	(symbol
		(lib_id "antmicroResistors0402:R_0R_0402")
		(at 154.94 163.83 0)
		(unit 1)
		(exclude_from_sim no)
		(in_bom yes)
		(on_board yes)
		(dnp no)
		(property "Reference" "R134"
			(at 152.4 165.1 0)
			(effects
				(font
					(size 1.27 1.27)
					(thickness 0.15)
				)
			)
		)
		(property "Value" "R_0R_0402"
			(at 175.26 176.53 0)
			(effects
				(font
					(size 1.27 1.27)
					(thickness 0.15)
				)
				(justify left bottom)
				(hide yes)
			)
		)
		(property "Footprint" "antmicro-footprints:R_0402_1005Metric"
			(at 175.26 179.07 0)
			(effects
				(font
					(size 1.27 1.27)
					(thickness 0.15)
				)
				(justify left bottom)
				(hide yes)
			)
		)
		(property "Datasheet" "https://industrial.panasonic.com/cdbs/www-data/pdf/RDA0000/AOA0000C301.pdf"
			(at 175.26 181.61 0)
			(effects
				(font
					(size 1.27 1.27)
					(thickness 0.15)
				)
				(justify left bottom)
				(hide yes)
			)
		)
		(property "Description" ""
			(at 154.94 163.83 0)
			(effects
				(font
					(size 1.27 1.27)
				)
				(hide yes)
			)
		)
		(property "MPN" "ERJ2GE0R00X"
			(at 175.26 184.15 0)
			(effects
				(font
					(size 1.27 1.27)
					(thickness 0.15)
				)
				(justify left bottom)
				(hide yes)
			)
		)
		(property "Manufacturer" "Panasonic"
			(at 175.26 186.69 0)
			(effects
				(font
					(size 1.27 1.27)
					(thickness 0.15)
				)
				(justify left bottom)
				(hide yes)
			)
		)
		(property "License" "Apache-2.0"
			(at 175.26 189.23 0)
			(effects
				(font
					(size 1.27 1.27)
					(thickness 0.15)
				)
				(justify left bottom)
				(hide yes)
			)
		)
		(property "Val" "0R"
			(at 161.29 165.1 0)
			(effects
				(font
					(size 1.27 1.27)
					(thickness 0.15)
				)
			)
		)
		(property "Tolerance" "~"
			(at 175.26 173.99 0)
			(effects
				(font
					(size 1.27 1.27)
				)
				(justify left bottom)
				(hide yes)
			)
		)
		(property "Current" "1A"
			(at 157.48 160.655 0)
			(effects
				(font
					(size 1.27 1.27)
					(thickness 0.15)
				)
				(hide yes)
			)
		)
		(property "Author" "Antmicro"
			(at 175.26 191.77 0)
			(effects
				(font
					(size 1.27 1.27)
					(thickness 0.15)
				)
				(justify left bottom)
				(hide yes)
			)
		)
		(property "Public" "False"
			(at 175.26 194.31 0)
			(effects
				(font
					(size 1.27 1.27)
				)
				(justify left bottom)
				(hide yes)
			)
		)
		(pin "1"
		)
		(pin "2"
		)
		(instances
			(project "com-express-7-baseboard"
				(path ""
					(reference "R134")
					(unit 1)
				)
			)
		)
	)
	(symbol
		(lib_id "antmicroModules:Mech_M2_2230_H2.5mm")
		(at 250.19 214.63 0)
		(unit 1)
		(exclude_from_sim no)
		(in_bom no)
		(on_board yes)
		(dnp yes)
		(property "Reference" "A4"
			(at 261.62 215.2649 0)
			(effects
				(font
					(size 1.27 1.27)
					(thickness 0.15)
				)
				(justify left)
			)
		)
		(property "Value" "Mech_M2_2230_H2.5mm"
			(at 261.62 217.8049 0)
			(effects
				(font
					(size 1.27 1.27)
					(thickness 0.15)
				)
				(justify left)
			)
		)
		(property "Footprint" "antmicro-footprints:Mech_M2_2230_H2.5mm"
			(at 275.59 219.71 0)
			(effects
				(font
					(size 1.27 1.27)
					(thickness 0.15)
				)
				(justify left bottom)
				(hide yes)
			)
		)
		(property "Datasheet" ""
			(at 275.59 222.25 0)
			(effects
				(font
					(size 1.27 1.27)
					(thickness 0.15)
				)
				(justify left bottom)
				(hide yes)
			)
		)
		(property "Description" ""
			(at 250.19 214.63 0)
			(effects
				(font
					(size 1.27 1.27)
				)
				(hide yes)
			)
		)
		(property "License" "Apache-2.0"
			(at 275.59 227.33 0)
			(effects
				(font
					(size 1.27 1.27)
					(thickness 0.15)
				)
				(justify left bottom)
				(hide yes)
			)
		)
		(property "Manufacturer" "None"
			(at 261.62 220.3449 0)
			(effects
				(font
					(size 1.27 1.27)
				)
				(justify left)
				(hide yes)
			)
		)
		(property "MPN" ""
			(at 250.19 214.63 0)
			(effects
				(font
					(size 1.27 1.27)
				)
			)
		)
		(property "Author" "Antmicro"
			(at 275.59 224.79 0)
			(effects
				(font
					(size 1.27 1.27)
					(thickness 0.15)
				)
				(justify left bottom)
				(hide yes)
			)
		)
		(property "Public" "False"
			(at 275.59 229.87 0)
			(effects
				(font
					(size 1.27 1.27)
				)
				(justify left bottom)
				(hide yes)
			)
		)
		(instances
			(project "com-express-7-baseboard"
				(path ""
					(reference "A4")
					(unit 1)
				)
			)
		)
	)
	(symbol
		(lib_id "antmicroCapacitors0603:C_22u_16V_0603")
		(at 238.76 82.55 90)
		(unit 1)
		(exclude_from_sim no)
		(in_bom yes)
		(on_board yes)
		(dnp no)
		(fields_autoplaced yes)
		(property "Reference" "C81"
			(at 241.3 78.7336 90)
			(effects
				(font
					(size 1.27 1.27)
					(thickness 0.15)
				)
				(justify right)
			)
		)
		(property "Value" "C_22u_16V_0603"
			(at 248.92 62.23 0)
			(effects
				(font
					(size 1.27 1.27)
					(thickness 0.15)
				)
				(justify left bottom)
				(hide yes)
			)
		)
		(property "Footprint" "antmicro-footprints:C_0603_1608Metric"
			(at 251.46 62.23 0)
			(effects
				(font
					(size 1.27 1.27)
					(thickness 0.15)
				)
				(justify left bottom)
				(hide yes)
			)
		)
		(property "Datasheet" "https://product.samsungsem.com/mlcc/CL10A226MO7JZN.do"
			(at 254 62.23 0)
			(effects
				(font
					(size 1.27 1.27)
					(thickness 0.15)
				)
				(justify left bottom)
				(hide yes)
			)
		)
		(property "Description" ""
			(at 238.76 82.55 0)
			(effects
				(font
					(size 1.27 1.27)
				)
				(hide yes)
			)
		)
		(property "MPN" "CL10A226MO7JZNC"
			(at 256.54 62.23 0)
			(effects
				(font
					(size 1.27 1.27)
					(thickness 0.15)
				)
				(justify left bottom)
				(hide yes)
			)
		)
		(property "Manufacturer" "Samsung Electro-Mechanics"
			(at 259.08 62.23 0)
			(effects
				(font
					(size 1.27 1.27)
					(thickness 0.15)
				)
				(justify left bottom)
				(hide yes)
			)
		)
		(property "License" "Apache-2.0"
			(at 261.62 62.23 0)
			(effects
				(font
					(size 1.27 1.27)
					(thickness 0.15)
				)
				(justify left bottom)
				(hide yes)
			)
		)
		(property "Author" "Antmicro"
			(at 264.16 62.23 0)
			(effects
				(font
					(size 1.27 1.27)
					(thickness 0.15)
				)
				(justify left bottom)
				(hide yes)
			)
		)
		(property "Val" "22u"
			(at 241.3 81.2736 90)
			(effects
				(font
					(size 1.27 1.27)
					(thickness 0.15)
				)
				(justify right)
			)
		)
		(property "Voltage" "16V"
			(at 266.7 62.23 0)
			(effects
				(font
					(size 1.27 1.27)
				)
				(justify left bottom)
				(hide yes)
			)
		)
		(property "Dielectric" ""
			(at 269.24 62.23 0)
			(effects
				(font
					(size 1.27 1.27)
				)
				(justify left bottom)
				(hide yes)
			)
		)
		(property "Public" "False"
			(at 271.78 62.23 0)
			(effects
				(font
					(size 1.27 1.27)
				)
				(justify left bottom)
				(hide yes)
			)
		)
		(pin "1"
		)
		(pin "2"
		)
		(instances
			(project "com-express-7-baseboard"
				(path ""
					(reference "C81")
					(unit 1)
				)
			)
		)
	)
	(symbol
		(lib_id "antmicroResistors0402:R_10k_0402")
		(at 175.26 81.28 90)
		(unit 1)
		(exclude_from_sim no)
		(in_bom yes)
		(on_board yes)
		(dnp no)
		(fields_autoplaced yes)
		(property "Reference" "R136"
			(at 177.8 76.2 90)
			(effects
				(font
					(size 1.27 1.27)
					(thickness 0.15)
				)
				(justify right)
			)
		)
		(property "Value" "R_10k_0402"
			(at 187.96 60.96 0)
			(effects
				(font
					(size 1.27 1.27)
					(thickness 0.15)
				)
				(justify left bottom)
				(hide yes)
			)
		)
		(property "Footprint" "antmicro-footprints:R_0402_1005Metric"
			(at 190.5 60.96 0)
			(effects
				(font
					(size 1.27 1.27)
					(thickness 0.15)
				)
				(justify left bottom)
				(hide yes)
			)
		)
		(property "Datasheet" "https://www.bourns.com/docs/product-datasheets/cr.pdf"
			(at 193.04 60.96 0)
			(effects
				(font
					(size 1.27 1.27)
					(thickness 0.15)
				)
				(justify left bottom)
				(hide yes)
			)
		)
		(property "Description" ""
			(at 175.26 81.28 0)
			(effects
				(font
					(size 1.27 1.27)
				)
				(hide yes)
			)
		)
		(property "MPN" "CR0402-FX-1002GLF"
			(at 195.58 60.96 0)
			(effects
				(font
					(size 1.27 1.27)
					(thickness 0.15)
				)
				(justify left bottom)
				(hide yes)
			)
		)
		(property "Manufacturer" "Bourns"
			(at 198.12 60.96 0)
			(effects
				(font
					(size 1.27 1.27)
					(thickness 0.15)
				)
				(justify left bottom)
				(hide yes)
			)
		)
		(property "License" "Apache-2.0"
			(at 200.66 60.96 0)
			(effects
				(font
					(size 1.27 1.27)
					(thickness 0.15)
				)
				(justify left bottom)
				(hide yes)
			)
		)
		(property "Author" "Antmicro"
			(at 203.2 60.96 0)
			(effects
				(font
					(size 1.27 1.27)
					(thickness 0.15)
				)
				(justify left bottom)
				(hide yes)
			)
		)
		(property "Val" "10k"
			(at 177.8 78.74 90)
			(effects
				(font
					(size 1.27 1.27)
					(thickness 0.15)
				)
				(justify right)
			)
		)
		(property "Tolerance" "1%"
			(at 185.42 60.96 0)
			(effects
				(font
					(size 1.27 1.27)
				)
				(justify left bottom)
				(hide yes)
			)
		)
		(property "Public" "False"
			(at 205.74 60.96 0)
			(effects
				(font
					(size 1.27 1.27)
				)
				(justify left bottom)
				(hide yes)
			)
		)
		(pin "2"
		)
		(pin "1"
		)
		(instances
			(project "com-express-7-baseboard"
				(path ""
					(reference "R136")
					(unit 1)
				)
			)
		)
	)
	(symbol
		(lib_id "antmicroResistors0402:R_0R_0402")
		(at 222.25 95.25 0)
		(unit 1)
		(exclude_from_sim no)
		(in_bom yes)
		(on_board yes)
		(dnp no)
		(property "Reference" "R137"
			(at 218.44 93.98 0)
			(effects
				(font
					(size 1.27 1.27)
					(thickness 0.15)
				)
			)
		)
		(property "Value" "R_0R_0402"
			(at 242.57 107.95 0)
			(effects
				(font
					(size 1.27 1.27)
					(thickness 0.15)
				)
				(justify left bottom)
				(hide yes)
			)
		)
		(property "Footprint" "antmicro-footprints:R_0402_1005Metric"
			(at 242.57 110.49 0)
			(effects
				(font
					(size 1.27 1.27)
					(thickness 0.15)
				)
				(justify left bottom)
				(hide yes)
			)
		)
		(property "Datasheet" "https://industrial.panasonic.com/cdbs/www-data/pdf/RDA0000/AOA0000C301.pdf"
			(at 242.57 113.03 0)
			(effects
				(font
					(size 1.27 1.27)
					(thickness 0.15)
				)
				(justify left bottom)
				(hide yes)
			)
		)
		(property "Description" ""
			(at 222.25 95.25 0)
			(effects
				(font
					(size 1.27 1.27)
				)
				(hide yes)
			)
		)
		(property "MPN" "ERJ2GE0R00X"
			(at 242.57 115.57 0)
			(effects
				(font
					(size 1.27 1.27)
					(thickness 0.15)
				)
				(justify left bottom)
				(hide yes)
			)
		)
		(property "Manufacturer" "Panasonic"
			(at 242.57 118.11 0)
			(effects
				(font
					(size 1.27 1.27)
					(thickness 0.15)
				)
				(justify left bottom)
				(hide yes)
			)
		)
		(property "License" "Apache-2.0"
			(at 242.57 120.65 0)
			(effects
				(font
					(size 1.27 1.27)
					(thickness 0.15)
				)
				(justify left bottom)
				(hide yes)
			)
		)
		(property "Val" "0R"
			(at 228.6 93.98 0)
			(effects
				(font
					(size 1.27 1.27)
					(thickness 0.15)
				)
			)
		)
		(property "Tolerance" "~"
			(at 242.57 105.41 0)
			(effects
				(font
					(size 1.27 1.27)
				)
				(justify left bottom)
				(hide yes)
			)
		)
		(property "Current" "1A"
			(at 224.79 91.44 0)
			(effects
				(font
					(size 1.27 1.27)
					(thickness 0.15)
				)
				(hide yes)
			)
		)
		(property "Author" "Antmicro"
			(at 242.57 123.19 0)
			(effects
				(font
					(size 1.27 1.27)
					(thickness 0.15)
				)
				(justify left bottom)
				(hide yes)
			)
		)
		(property "Public" "False"
			(at 242.57 125.73 0)
			(effects
				(font
					(size 1.27 1.27)
				)
				(justify left bottom)
				(hide yes)
			)
		)
		(pin "1"
		)
		(pin "2"
		)
		(instances
			(project "com-express-7-baseboard"
				(path ""
					(reference "R137")
					(unit 1)
				)
			)
		)
	)
	(symbol
		(lib_id "antmicropower:GND")
		(at 229.87 83.82 0)
		(unit 1)
		(exclude_from_sim no)
		(in_bom yes)
		(on_board yes)
		(dnp no)
		(property "Reference" "#PWR0177"
			(at 229.87 90.17 0)
			(effects
				(font
					(size 1.27 1.27)
				)
				(hide yes)
			)
		)
		(property "Value" "GND"
			(at 229.87 87.63 0)
			(effects
				(font
					(size 1.27 1.27)
				)
			)
		)
		(property "Footprint" ""
			(at 229.87 83.82 0)
			(effects
				(font
					(size 1.27 1.27)
				)
				(hide yes)
			)
		)
		(property "Datasheet" ""
			(at 229.87 83.82 0)
			(effects
				(font
					(size 1.27 1.27)
				)
				(hide yes)
			)
		)
		(property "Description" ""
			(at 229.87 83.82 0)
			(effects
				(font
					(size 1.27 1.27)
				)
				(hide yes)
			)
		)
		(property "Author" "Antmicro"
			(at 238.76 91.44 0)
			(effects
				(font
					(size 1.27 1.27)
					(thickness 0.15)
				)
				(justify left bottom)
				(hide yes)
			)
		)
		(property "License" "Apache-2.0"
			(at 238.76 93.98 0)
			(effects
				(font
					(size 1.27 1.27)
					(thickness 0.15)
				)
				(justify left bottom)
				(hide yes)
			)
		)
		(pin "1"
		)
		(instances
			(project "com-express-7-baseboard"
				(path ""
					(reference "#PWR0177")
					(unit 1)
				)
			)
		)
	)
)
